#ISCELL
  mstr_misc dns *
  *
#ISCELL
  pure_quanta quanta_title_block_c *
  *
#ISCELL
  standard offpage *
  page169_i10
#ISCELL
  pure_quanta_power universal_gnd *
  page169_i105
#CELL
  pure_quanta q_capp *
  page169_i106
#CELL
  pure_quanta q_capp *
  page169_i107
#ISCELL
  pure_quanta_power vcc_core *
  page169_i109
#CELL
  pure_quanta q_res *
  page169_i11
#ISCELL
  pure_quanta_power universal_gnd *
  page169_i110
#CELL
  pure_quanta q_capp *
  page169_i112
#CELL
  pure_quanta q_cap *
  page169_i113
#CELL
  pure_quanta q_cap *
  page169_i114
#CELL
  pure_quanta q_cap *
  page169_i115
#ISCELL
  pure_quanta_power universal_gnd *
  page169_i116
#ISCELL
  pure_quanta_power universal_gnd *
  page169_i117
#CELL
  pure_quanta q_res *
  page169_i118
#CELL
  pure_quanta q_cap *
  page169_i119
#ISCELL
  pure_quanta_power universal_gnd *
  page169_i12
#ISCELL
  pure_quanta_power vcc_core *
  page169_i120
#CELL
  pure_quanta isl99390frztr5935 *
  page169_i121
#CELL
  pure_quanta isl99390frztr5935 *
  page169_i122
#CELL
  pure_quanta q_capp *
  page169_i123
#ISCELL
  standard offpage *
  page169_i124
#CELL
  pure_quanta q_cap *
  page169_i125
#CELL
  pure_quanta q_res *
  page169_i126
#ISCELL
  pure_quanta_power universal_gnd *
  page169_i127
#CELL
  pure_quanta q_cap *
  page169_i128
#ISCELL
  pure_quanta_power universal_gnd *
  page169_i129
#CELL
  pure_quanta q_cap *
  page169_i13
#CELL
  pure_quanta q_res *
  page169_i130
#ISCELL
  standard offpage *
  page169_i131
#CELL
  pure_quanta q_res *
  page169_i132
#CELL
  pure_quanta q_res *
  page169_i133
#ISCELL
  pure_quanta_power vcc_core *
  page169_i134
#ISCELL
  pure_quanta_power vcc_core *
  page169_i135
#CELL
  pure_quanta q_res *
  page169_i136
#ISCELL
  pure_quanta_power universal_gnd *
  page169_i14
#ISCELL
  pure_quanta_power universal_gnd *
  page169_i15
#CELL
  pure_quanta q_res *
  page169_i16
#CELL
  pure_quanta q_cap *
  page169_i17
#CELL
  pure_quanta q_cap *
  page169_i18
#CELL
  pure_quanta q_cap *
  page169_i19
#CELL
  pure_quanta q_cap *
  page169_i2
#CELL
  pure_quanta q_cap *
  page169_i20
#CELL
  pure_quanta q_cap *
  page169_i21
#CELL
  pure_quanta q_inductor *
  page169_i24
#ISCELL
  pure_quanta_power vcc_core *
  page169_i25
#CELL
  pure_quanta q_capp *
  page169_i26
#CELL
  pure_quanta q_capp *
  page169_i27
#CELL
  pure_quanta q_res *
  page169_i3
#ISCELL
  pure_quanta_power vcc_core *
  page169_i30
#CELL
  pure_quanta q_inductor4p_14 *
  page169_i31
#CELL
  pure_quanta q_cap *
  page169_i32
#CELL
  pure_quanta q_cap *
  page169_i33
#CELL
  pure_quanta q_cap *
  page169_i35
#ISCELL
  pure_quanta_power universal_gnd *
  page169_i36
#ISCELL
  pure_quanta_power vcc_core *
  page169_i37
#ISCELL
  standard offpage *
  page169_i39
#CELL
  pure_quanta q_cap *
  page169_i4
#CELL
  pure_quanta q_res *
  page169_i40
#ISCELL
  standard offpage *
  page169_i41
#ISCELL
  pure_quanta_power vcc_core *
  page169_i47
#CELL
  pure_quanta q_cap *
  page169_i48
#ISCELL
  pure_quanta_power universal_gnd *
  page169_i49
#ISCELL
  pure_quanta_power universal_gnd *
  page169_i5
#CELL
  pure_quanta q_cap *
  page169_i50
#ISCELL
  pure_quanta_power vcc_core *
  page169_i54
#ISCELL
  pure_quanta_power universal_gnd *
  page169_i56
#ISCELL
  pure_quanta_power vcc_core *
  page169_i6
#CELL
  pure_quanta q_cap *
  page169_i62
#CELL
  pure_quanta q_inductor4p_14 *
  page169_i63
#CELL
  pure_quanta q_cap *
  page169_i64
#CELL
  pure_quanta q_cap *
  page169_i65
#CELL
  pure_quanta q_cap *
  page169_i66
#CELL
  pure_quanta q_cap *
  page169_i67
#CELL
  pure_quanta q_res *
  page169_i68
#ISCELL
  pure_quanta_power universal_gnd *
  page169_i7
#CELL
  pure_quanta q_res *
  page169_i71
#CELL
  pure_quanta q_res *
  page169_i75
#ISCELL
  standard offpage *
  page169_i8
#ISCELL
  standard offpage *
  page169_i80
#ISCELL
  standard offpage *
  page169_i83
#ISCELL
  pure_quanta_power universal_gnd *
  page169_i84
#ISCELL
  pure_quanta_power universal_gnd *
  page169_i85
#CELL
  pure_quanta q_cap *
  page169_i86
#ISCELL
  standard offpage *
  page169_i87
#ISCELL
  pure_quanta_power universal_gnd *
  page169_i88
#ISCELL
  standard offpage *
  page169_i89
#ISCELL
  standard offpage *
  page169_i9
#ISCELL
  standard offpage *
  page169_i91
#CELL
  pure_quanta q_capp *
  page169_i92
